(kicad_pcb
	(version 20260206)
	(generator "pcbnew")
	(generator_version "10.0")
	(general
		(thickness 1.6)
		(legacy_teardrops no)
	)
	(paper "A4")
	(title_block
		(title "01162023_DA0F0TEBIF0_F0T_Expander_BD_F_brd_V02_OCP.brd")
		(comment 1 "Grand Teton / footprints 2911-2916 of 9728")
	)
	(layers
		(0 "F.Cu" signal "TOP")
		(4 "In1.Cu" signal "GND")
		(6 "In2.Cu" signal "VCC")
		(8 "In3.Cu" signal "VCC1")
		(10 "In4.Cu" signal "GND1")
		(12 "In5.Cu" signal "IN1")
		(14 "In6.Cu" signal "GND2")
		(16 "In7.Cu" signal "IN2")
		(18 "In8.Cu" signal "GND3")
		(20 "In9.Cu" signal "IN3")
		(22 "In10.Cu" signal "GND4")
		(24 "In11.Cu" signal "IN4")
		(26 "In12.Cu" signal "GND5")
		(28 "In13.Cu" signal "IN5")
		(30 "In14.Cu" signal "GND6")
		(32 "In15.Cu" signal "IN6")
		(34 "In16.Cu" signal "GND7")
		(2 "B.Cu" signal "BOTTOM")
		(9 "F.Adhes" user "F.Adhesive")
		(11 "B.Adhes" user "B.Adhesive")
		(13 "F.Paste" user "Package Geometry/Pastemask Top")
		(15 "B.Paste" user "Package Geometry/Pastemask Bottom")
		(5 "F.SilkS" user "Ref Des/Silkscreen Top")
		(7 "B.SilkS" user "Ref Des/Silkscreen Bottom")
		(1 "F.Mask" user "Board Geometry/Soldermask Top")
		(3 "B.Mask" user "Board Geometry/Soldermask Bottom")
		(17 "Dwgs.User" user "User.Drawings")
		(19 "Cmts.User" user "User.Comments")
		(21 "Eco1.User" user "User.Eco1")
		(23 "Eco2.User" user "User.Eco2")
		(25 "Edge.Cuts" user "Board Geometry/Outline")
		(27 "Margin" user)
		(31 "F.CrtYd" user "Package Geometry/Place Bound Top")
		(29 "B.CrtYd" user "Package Geometry/Place Bound Bottom")
		(35 "F.Fab" user "Ref Des/Assembly Top")
		(33 "B.Fab" user "Ref Des/Assembly Bottom")
	)
	(footprint ""
		(layer "F.Cu")
		(at 62.491874 -161.881566 90)
		(property "Reference" "Q119"
			(at -0.185166 2.025396 90)
			(unlocked yes)
			(layer "F.SilkS")
			(effects
				(font
					(size 0.7874 0.5842)
					(thickness 0.1524)
				)
			)
		)
		(property "Value" ""
			(at 0 0 90)
			(layer "F.Fab")
			(effects
				(font
					(size 1.27 1.27)
				)
			)
		)
		(duplicate_pad_numbers_are_jumpers no)
		(fp_line
			(start 1.376172 -1.199896)
			(end 1.376172 1.199896)
			(stroke
				(width 0.1524)
				(type default)
			)
			(layer "F.SilkS")
		)
		(fp_line
			(start 0.508 -1.199896)
			(end 1.376172 -1.199896)
			(stroke
				(width 0.1524)
				(type default)
			)
			(layer "F.SilkS")
		)
		(fp_line
			(start -0.508 -1.199896)
			(end 0 -0.762)
			(stroke
				(width 0.1524)
				(type default)
			)
			(layer "F.SilkS")
		)
		(fp_line
			(start -1.376172 -1.199896)
			(end -0.508 -1.199896)
			(stroke
				(width 0.1524)
				(type default)
			)
			(layer "F.SilkS")
		)
		(fp_line
			(start 0 -0.762)
			(end 0.508 -1.199896)
			(stroke
				(width 0.1524)
				(type default)
			)
			(layer "F.SilkS")
		)
		(fp_line
			(start 1.376172 1.199896)
			(end -1.376172 1.199896)
			(stroke
				(width 0.1524)
				(type default)
			)
			(layer "F.SilkS")
		)
		(fp_line
			(start -1.376172 1.199896)
			(end -1.376172 -1.199896)
			(stroke
				(width 0.1524)
				(type default)
			)
			(layer "F.SilkS")
		)
		(fp_poly
			(pts
				(xy -1.3208 -1.364488) (xy -1.590294 -2.172716) (xy -2.129028 -1.633982)
			)
			(stroke
				(width 0)
				(type default)
			)
			(fill yes)
			(layer "F.SilkS")
		)
		(fp_line
			(start 0.674878 -1.100074)
			(end 0.674878 1.100074)
			(stroke
				(width 0.1)
				(type default)
			)
			(layer "F.Fab")
		)
		(fp_line
			(start -0.674878 -1.100074)
			(end 0.674878 -1.100074)
			(stroke
				(width 0.1)
				(type default)
			)
			(layer "F.Fab")
		)
		(fp_line
			(start 0.674878 1.100074)
			(end -0.674878 1.100074)
			(stroke
				(width 0.1)
				(type default)
			)
			(layer "F.Fab")
		)
		(fp_line
			(start -0.674878 1.100074)
			(end -0.674878 -1.100074)
			(stroke
				(width 0.1)
				(type default)
			)
			(layer "F.Fab")
		)
		(fp_poly
			(pts
				(xy -1.4605 -0.7493) (xy -2.2225 -1.1303) (xy -2.2225 -0.3683)
			)
			(stroke
				(width 0)
				(type default)
			)
			(fill yes)
			(layer "F.Fab")
		)
		(pad "1" smd rect
			(at -0.899922 -0.750062)
			(size 0.6096 0.6096)
			(layers "F.Cu" "F.Mask" "F.Paste")
			(net "GND")
		)
		(pad "2" smd rect
			(at -0.899922 0)
			(size 0.4064 0.6096)
			(layers "F.Cu" "F.Mask" "F.Paste")
			(net "FM_SYS_THROTTLE_NIC0")
		)
		(pad "3" smd rect
			(at -0.899922 0.750062)
			(size 0.6096 0.6096)
			(layers "F.Cu" "F.Mask" "F.Paste")
			(net "NIC1_PWRBRK_N")
		)
		(pad "4" smd rect
			(at 0.899922 0.750062)
			(size 0.6096 0.6096)
			(layers "F.Cu" "F.Mask" "F.Paste")
			(net "GND")
		)
		(pad "5" smd rect
			(at 0.899922 0)
			(size 0.4064 0.6096)
			(layers "F.Cu" "F.Mask" "F.Paste")
			(net "FM_SYS_THROTTLE_NIC1")
		)
		(pad "6" smd rect
			(at 0.899922 -0.750062)
			(size 0.6096 0.6096)
			(layers "F.Cu" "F.Mask" "F.Paste")
			(net "NIC0_PWRBRK_N")
		)
	)
	(footprint ""
		(layer "F.Cu")
		(at 245.406164 -134.434326)
		(property "Reference" "PC342"
			(at 0 0 0)
			(layer "F.SilkS")
			(hide yes)
			(effects
				(font
					(size 1.27 1.27)
				)
			)
		)
		(property "Value" ""
			(at 0 0 0)
			(layer "F.Fab")
			(effects
				(font
					(size 1.27 1.27)
				)
			)
		)
		(duplicate_pad_numbers_are_jumpers no)
		(fp_line
			(start -0.7874 -0.4064)
			(end 0.7874 -0.4064)
			(stroke
				(width 0.1524)
				(type default)
			)
			(layer "F.SilkS")
		)
		(fp_line
			(start -0.7874 0.4064)
			(end -0.7874 -0.4064)
			(stroke
				(width 0.1524)
				(type default)
			)
			(layer "F.SilkS")
		)
		(fp_line
			(start 0.7874 -0.4064)
			(end 0.7874 0.4064)
			(stroke
				(width 0.1524)
				(type default)
			)
			(layer "F.SilkS")
		)
		(fp_line
			(start 0.7874 0.4064)
			(end -0.7874 0.4064)
			(stroke
				(width 0.1524)
				(type default)
			)
			(layer "F.SilkS")
		)
		(fp_line
			(start -0.67945 -0.305054)
			(end -0.12065 -0.305054)
			(stroke
				(width 0.1)
				(type default)
			)
			(layer "F.Fab")
		)
		(fp_line
			(start -0.67945 0.3048)
			(end -0.67945 -0.305054)
			(stroke
				(width 0.1)
				(type default)
			)
			(layer "F.Fab")
		)
		(fp_line
			(start -0.12065 -0.305054)
			(end -0.12065 -0.2794)
			(stroke
				(width 0.1)
				(type default)
			)
			(layer "F.Fab")
		)
		(fp_line
			(start -0.12065 -0.2794)
			(end 0.12065 -0.2794)
			(stroke
				(width 0.1)
				(type default)
			)
			(layer "F.Fab")
		)
		(fp_line
			(start -0.12065 0.2794)
			(end -0.12065 0.3048)
			(stroke
				(width 0.1)
				(type default)
			)
			(layer "F.Fab")
		)
		(fp_line
			(start -0.12065 0.3048)
			(end -0.67945 0.3048)
			(stroke
				(width 0.1)
				(type default)
			)
			(layer "F.Fab")
		)
		(fp_line
			(start 0.120396 0.2794)
			(end -0.12065 0.2794)
			(stroke
				(width 0.1)
				(type default)
			)
			(layer "F.Fab")
		)
		(fp_line
			(start 0.120396 0.3048)
			(end 0.120396 0.2794)
			(stroke
				(width 0.1)
				(type default)
			)
			(layer "F.Fab")
		)
		(fp_line
			(start 0.12065 -0.3048)
			(end 0.67945 -0.3048)
			(stroke
				(width 0.1)
				(type default)
			)
			(layer "F.Fab")
		)
		(fp_line
			(start 0.12065 -0.2794)
			(end 0.12065 -0.3048)
			(stroke
				(width 0.1)
				(type default)
			)
			(layer "F.Fab")
		)
		(fp_line
			(start 0.67945 -0.3048)
			(end 0.67945 0.3048)
			(stroke
				(width 0.1)
				(type default)
			)
			(layer "F.Fab")
		)
		(fp_line
			(start 0.67945 0.3048)
			(end 0.120396 0.3048)
			(stroke
				(width 0.1)
				(type default)
			)
			(layer "F.Fab")
		)
		(pad "1" smd circle
			(at -0.40005 0)
			(size 0 0)
			(layers "F.Cu" "F.Mask" "F.Paste")
			(net "P12V_AUX")
		)
		(pad "2" smd circle
			(at 0.40005 0)
			(size 0 0)
			(layers "F.Cu" "F.Mask" "F.Paste")
			(net "GND")
		)
	)
	(footprint ""
		(layer "F.Cu")
		(at 380.711456 -293.245032 -90)
		(property "Reference" "R4590"
			(at 0 0 270)
			(layer "F.SilkS")
			(hide yes)
			(effects
				(font
					(size 1.27 1.27)
				)
			)
		)
		(property "Value" ""
			(at 0 0 270)
			(layer "F.Fab")
			(effects
				(font
					(size 1.27 1.27)
				)
			)
		)
		(duplicate_pad_numbers_are_jumpers no)
		(fp_line
			(start -0.7874 0.4064)
			(end -0.7874 -0.4064)
			(stroke
				(width 0.1524)
				(type default)
			)
			(layer "F.SilkS")
		)
		(fp_line
			(start 0.7874 0.4064)
			(end -0.7874 0.4064)
			(stroke
				(width 0.1524)
				(type default)
			)
			(layer "F.SilkS")
		)
		(fp_line
			(start -0.7874 -0.4064)
			(end 0.7874 -0.4064)
			(stroke
				(width 0.1524)
				(type default)
			)
			(layer "F.SilkS")
		)
		(fp_line
			(start 0.7874 -0.4064)
			(end 0.7874 0.4064)
			(stroke
				(width 0.1524)
				(type default)
			)
			(layer "F.SilkS")
		)
		(fp_line
			(start -0.67945 0.3048)
			(end -0.67945 -0.305054)
			(stroke
				(width 0.1)
				(type default)
			)
			(layer "F.Fab")
		)
		(fp_line
			(start -0.12065 0.3048)
			(end -0.67945 0.3048)
			(stroke
				(width 0.1)
				(type default)
			)
			(layer "F.Fab")
		)
		(fp_line
			(start 0.120396 0.3048)
			(end 0.120396 0.2794)
			(stroke
				(width 0.1)
				(type default)
			)
			(layer "F.Fab")
		)
		(fp_line
			(start 0.67945 0.3048)
			(end 0.120396 0.3048)
			(stroke
				(width 0.1)
				(type default)
			)
			(layer "F.Fab")
		)
		(fp_line
			(start -0.12065 0.2794)
			(end -0.12065 0.3048)
			(stroke
				(width 0.1)
				(type default)
			)
			(layer "F.Fab")
		)
		(fp_line
			(start 0.120396 0.2794)
			(end -0.12065 0.2794)
			(stroke
				(width 0.1)
				(type default)
			)
			(layer "F.Fab")
		)
		(fp_line
			(start -0.12065 -0.2794)
			(end 0.12065 -0.2794)
			(stroke
				(width 0.1)
				(type default)
			)
			(layer "F.Fab")
		)
		(fp_line
			(start 0.12065 -0.2794)
			(end 0.12065 -0.3048)
			(stroke
				(width 0.1)
				(type default)
			)
			(layer "F.Fab")
		)
		(fp_line
			(start 0.12065 -0.3048)
			(end 0.67945 -0.3048)
			(stroke
				(width 0.1)
				(type default)
			)
			(layer "F.Fab")
		)
		(fp_line
			(start 0.67945 -0.3048)
			(end 0.67945 0.3048)
			(stroke
				(width 0.1)
				(type default)
			)
			(layer "F.Fab")
		)
		(fp_line
			(start -0.67945 -0.305054)
			(end -0.12065 -0.305054)
			(stroke
				(width 0.1)
				(type default)
			)
			(layer "F.Fab")
		)
		(fp_line
			(start -0.12065 -0.305054)
			(end -0.12065 -0.2794)
			(stroke
				(width 0.1)
				(type default)
			)
			(layer "F.Fab")
		)
		(pad "1" smd circle
			(at -0.40005 0 270)
			(size 0 0)
			(layers "F.Cu" "F.Mask" "F.Paste")
			(net "PCEPLL2_VDDA18_PEX3")
		)
		(pad "2" smd circle
			(at 0.40005 0 270)
			(size 0 0)
			(layers "F.Cu" "F.Mask" "F.Paste")
			(net "PCEPLL2_VDDA18_PEX3_R")
		)
	)
	(footprint ""
		(layer "F.Cu")
		(at 168.12514 -14.735302 180)
		(property "Reference" "C2722"
			(at 0 0 180)
			(layer "F.SilkS")
			(hide yes)
			(effects
				(font
					(size 1.27 1.27)
				)
			)
		)
		(property "Value" ""
			(at 0 0 180)
			(layer "F.Fab")
			(effects
				(font
					(size 1.27 1.27)
				)
			)
		)
		(duplicate_pad_numbers_are_jumpers no)
		(fp_line
			(start 0.7874 0.4064)
			(end -0.7874 0.4064)
			(stroke
				(width 0.1524)
				(type default)
			)
			(layer "F.SilkS")
		)
		(fp_line
			(start 0.7874 -0.4064)
			(end 0.7874 0.4064)
			(stroke
				(width 0.1524)
				(type default)
			)
			(layer "F.SilkS")
		)
		(fp_line
			(start -0.7874 0.4064)
			(end -0.7874 -0.4064)
			(stroke
				(width 0.1524)
				(type default)
			)
			(layer "F.SilkS")
		)
		(fp_line
			(start -0.7874 -0.4064)
			(end 0.7874 -0.4064)
			(stroke
				(width 0.1524)
				(type default)
			)
			(layer "F.SilkS")
		)
		(fp_line
			(start 0.67945 0.3048)
			(end 0.120396 0.3048)
			(stroke
				(width 0.1)
				(type default)
			)
			(layer "F.Fab")
		)
		(fp_line
			(start 0.67945 -0.3048)
			(end 0.67945 0.3048)
			(stroke
				(width 0.1)
				(type default)
			)
			(layer "F.Fab")
		)
		(fp_line
			(start 0.12065 -0.2794)
			(end 0.12065 -0.3048)
			(stroke
				(width 0.1)
				(type default)
			)
			(layer "F.Fab")
		)
		(fp_line
			(start 0.12065 -0.3048)
			(end 0.67945 -0.3048)
			(stroke
				(width 0.1)
				(type default)
			)
			(layer "F.Fab")
		)
		(fp_line
			(start 0.120396 0.3048)
			(end 0.120396 0.2794)
			(stroke
				(width 0.1)
				(type default)
			)
			(layer "F.Fab")
		)
		(fp_line
			(start 0.120396 0.2794)
			(end -0.12065 0.2794)
			(stroke
				(width 0.1)
				(type default)
			)
			(layer "F.Fab")
		)
		(fp_line
			(start -0.12065 0.3048)
			(end -0.67945 0.3048)
			(stroke
				(width 0.1)
				(type default)
			)
			(layer "F.Fab")
		)
		(fp_line
			(start -0.12065 0.2794)
			(end -0.12065 0.3048)
			(stroke
				(width 0.1)
				(type default)
			)
			(layer "F.Fab")
		)
		(fp_line
			(start -0.12065 -0.2794)
			(end 0.12065 -0.2794)
			(stroke
				(width 0.1)
				(type default)
			)
			(layer "F.Fab")
		)
		(fp_line
			(start -0.12065 -0.305054)
			(end -0.12065 -0.2794)
			(stroke
				(width 0.1)
				(type default)
			)
			(layer "F.Fab")
		)
		(fp_line
			(start -0.67945 0.3048)
			(end -0.67945 -0.305054)
			(stroke
				(width 0.1)
				(type default)
			)
			(layer "F.Fab")
		)
		(fp_line
			(start -0.67945 -0.305054)
			(end -0.12065 -0.305054)
			(stroke
				(width 0.1)
				(type default)
			)
			(layer "F.Fab")
		)
		(pad "1" smd circle
			(at -0.40005 0 180)
			(size 0 0)
			(layers "F.Cu" "F.Mask" "F.Paste")
			(net "GND")
		)
		(pad "2" smd circle
			(at 0.40005 0 180)
			(size 0 0)
			(layers "F.Cu" "F.Mask" "F.Paste")
			(net "P3V3_SSD5")
		)
	)
	(footprint ""
		(layer "F.Cu")
		(at 442.767466 -112.903508 90)
		(property "Reference" "PC347"
			(at 0 0 90)
			(layer "F.SilkS")
			(hide yes)
			(effects
				(font
					(size 1.27 1.27)
				)
			)
		)
		(property "Value" ""
			(at 0 0 90)
			(layer "F.Fab")
			(effects
				(font
					(size 1.27 1.27)
				)
			)
		)
		(duplicate_pad_numbers_are_jumpers no)
		(fp_line
			(start 1.524 -0.762)
			(end 1.524 0.762)
			(stroke
				(width 0.1524)
				(type default)
			)
			(layer "F.SilkS")
		)
		(fp_line
			(start -1.524 -0.762)
			(end 1.524 -0.762)
			(stroke
				(width 0.1524)
				(type default)
			)
			(layer "F.SilkS")
		)
		(fp_line
			(start 1.524 0.762)
			(end -1.524 0.762)
			(stroke
				(width 0.1524)
				(type default)
			)
			(layer "F.SilkS")
		)
		(fp_line
			(start -1.524 0.762)
			(end -1.524 -0.762)
			(stroke
				(width 0.1524)
				(type default)
			)
			(layer "F.SilkS")
		)
		(fp_line
			(start 1.1049 -0.724916)
			(end -1.1049 -0.724916)
			(stroke
				(width 0.1)
				(type default)
			)
			(layer "F.Fab")
		)
		(fp_line
			(start -1.1049 -0.724916)
			(end -1.1049 0.724916)
			(stroke
				(width 0.1)
				(type default)
			)
			(layer "F.Fab")
		)
		(fp_line
			(start 1.1049 0.724916)
			(end 1.1049 -0.724916)
			(stroke
				(width 0.1)
				(type default)
			)
			(layer "F.Fab")
		)
		(fp_line
			(start -1.1049 0.724916)
			(end 1.1049 0.724916)
			(stroke
				(width 0.1)
				(type default)
			)
			(layer "F.Fab")
		)
		(pad "1" smd rect
			(at -0.889 0 270)
			(size 1.016 1.27)
			(layers "F.Cu" "F.Mask" "F.Paste")
			(net "P12V_NIC7_R")
		)
		(pad "2" smd rect
			(at 0.889 0 270)
			(size 1.016 1.27)
			(layers "F.Cu" "F.Mask" "F.Paste")
			(net "GND")
		)
	)
	(footprint ""
		(layer "F.Cu")
		(at 327.53173 -224.988882 180)
		(property "Reference" "R4168"
			(at 0 0 180)
			(layer "F.SilkS")
			(hide yes)
			(effects
				(font
					(size 1.27 1.27)
				)
			)
		)
		(property "Value" ""
			(at 0 0 180)
			(layer "F.Fab")
			(effects
				(font
					(size 1.27 1.27)
				)
			)
		)
		(duplicate_pad_numbers_are_jumpers no)
		(fp_line
			(start 0.7874 0.4064)
			(end -0.7874 0.4064)
			(stroke
				(width 0.1524)
				(type default)
			)
			(layer "F.SilkS")
		)
		(fp_line
			(start 0.7874 -0.4064)
			(end 0.7874 0.4064)
			(stroke
				(width 0.1524)
				(type default)
			)
			(layer "F.SilkS")
		)
		(fp_line
			(start -0.7874 0.4064)
			(end -0.7874 -0.4064)
			(stroke
				(width 0.1524)
				(type default)
			)
			(layer "F.SilkS")
		)
		(fp_line
			(start -0.7874 -0.4064)
			(end 0.7874 -0.4064)
			(stroke
				(width 0.1524)
				(type default)
			)
			(layer "F.SilkS")
		)
		(fp_line
			(start 0.67945 0.3048)
			(end 0.120396 0.3048)
			(stroke
				(width 0.1)
				(type default)
			)
			(layer "F.Fab")
		)
		(fp_line
			(start 0.67945 -0.3048)
			(end 0.67945 0.3048)
			(stroke
				(width 0.1)
				(type default)
			)
			(layer "F.Fab")
		)
		(fp_line
			(start 0.12065 -0.2794)
			(end 0.12065 -0.3048)
			(stroke
				(width 0.1)
				(type default)
			)
			(layer "F.Fab")
		)
		(fp_line
			(start 0.12065 -0.3048)
			(end 0.67945 -0.3048)
			(stroke
				(width 0.1)
				(type default)
			)
			(layer "F.Fab")
		)
		(fp_line
			(start 0.120396 0.3048)
			(end 0.120396 0.2794)
			(stroke
				(width 0.1)
				(type default)
			)
			(layer "F.Fab")
		)
		(fp_line
			(start 0.120396 0.2794)
			(end -0.12065 0.2794)
			(stroke
				(width 0.1)
				(type default)
			)
			(layer "F.Fab")
		)
		(fp_line
			(start -0.12065 0.3048)
			(end -0.67945 0.3048)
			(stroke
				(width 0.1)
				(type default)
			)
			(layer "F.Fab")
		)
		(fp_line
			(start -0.12065 0.2794)
			(end -0.12065 0.3048)
			(stroke
				(width 0.1)
				(type default)
			)
			(layer "F.Fab")
		)
		(fp_line
			(start -0.12065 -0.2794)
			(end 0.12065 -0.2794)
			(stroke
				(width 0.1)
				(type default)
			)
			(layer "F.Fab")
		)
		(fp_line
			(start -0.12065 -0.305054)
			(end -0.12065 -0.2794)
			(stroke
				(width 0.1)
				(type default)
			)
			(layer "F.Fab")
		)
		(fp_line
			(start -0.67945 0.3048)
			(end -0.67945 -0.305054)
			(stroke
				(width 0.1)
				(type default)
			)
			(layer "F.Fab")
		)
		(fp_line
			(start -0.67945 -0.305054)
			(end -0.12065 -0.305054)
			(stroke
				(width 0.1)
				(type default)
			)
			(layer "F.Fab")
		)
		(pad "1" smd circle
			(at -0.40005 0 180)
			(size 0 0)
			(layers "F.Cu" "F.Mask" "F.Paste")
			(net "FM_CLK_EN")
		)
		(pad "2" smd circle
			(at 0.40005 0 180)
			(size 0 0)
			(layers "F.Cu" "F.Mask" "F.Paste")
			(net "FM_CLK_EN_R")
		)
	)
)
